FILE_TYPE=LIBRARY_PARTS;
primitive 'CONN9_H51826001','CONN9_H51826001_IO','CONN9_H51826001_PIP1';
  pin
    'IO1':
      PIN_NUMBER='(1)';
      BIDIRECTIONAL='TRUE';
      INPUT_LOAD='(-0.01,0.01)';
      OUTPUT_LOAD='(1.0,-1.0)';
    'IO2':
      PIN_NUMBER='(2)';
      BIDIRECTIONAL='TRUE';
      INPUT_LOAD='(-0.01,0.01)';
      OUTPUT_LOAD='(1.0,-1.0)';
    'IO3':
      PIN_NUMBER='(3)';
      BIDIRECTIONAL='TRUE';
      INPUT_LOAD='(-0.01,0.01)';
      OUTPUT_LOAD='(1.0,-1.0)';
    'IO4':
      PIN_NUMBER='(4)';
      BIDIRECTIONAL='TRUE';
      INPUT_LOAD='(-0.01,0.01)';
      OUTPUT_LOAD='(1.0,-1.0)';
    'IO5':
      PIN_NUMBER='(5)';
      BIDIRECTIONAL='TRUE';
      INPUT_LOAD='(-0.01,0.01)';
      OUTPUT_LOAD='(1.0,-1.0)';
    'IO6':
      PIN_NUMBER='(6)';
      BIDIRECTIONAL='TRUE';
      INPUT_LOAD='(-0.01,0.01)';
      OUTPUT_LOAD='(1.0,-1.0)';
    'IO7':
      PIN_NUMBER='(7)';
      BIDIRECTIONAL='TRUE';
      INPUT_LOAD='(-0.01,0.01)';
      OUTPUT_LOAD='(1.0,-1.0)';
    'IO8':
      PIN_NUMBER='(8)';
      BIDIRECTIONAL='TRUE';
      INPUT_LOAD='(-0.01,0.01)';
      OUTPUT_LOAD='(1.0,-1.0)';
    'IO9':
      PIN_NUMBER='(9)';
      BIDIRECTIONAL='TRUE';
      INPUT_LOAD='(-0.01,0.01)';
      OUTPUT_LOAD='(1.0,-1.0)';
    'MH1':
      PIN_NUMBER='(MH1)';
      PINUSE='GROUND';
      NO_LOAD_CHECK='Both';
      NO_IO_CHECK='Both';
      NO_ASSERT_CHECK='TRUE';
      NO_DIR_CHECK='TRUE';
      ALLOW_CONNECT='TRUE';
    'MH2':
      PIN_NUMBER='(MH2)';
      PINUSE='GROUND';
      NO_LOAD_CHECK='Both';
      NO_IO_CHECK='Both';
      NO_ASSERT_CHECK='TRUE';
      NO_DIR_CHECK='TRUE';
      ALLOW_CONNECT='TRUE';
    'MH3':
      PIN_NUMBER='(MH3)';
      PINUSE='GROUND';
      NO_LOAD_CHECK='Both';
      NO_IO_CHECK='Both';
      NO_ASSERT_CHECK='TRUE';
      NO_DIR_CHECK='TRUE';
      ALLOW_CONNECT='TRUE';
    'MH4':
      PIN_NUMBER='(MH4)';
      PINUSE='GROUND';
      NO_LOAD_CHECK='Both';
      NO_IO_CHECK='Both';
      NO_ASSERT_CHECK='TRUE';
      NO_DIR_CHECK='TRUE';
      ALLOW_CONNECT='TRUE';
  end_pin;
  body
    PART_NAME='CONN9_H51826001';
    PHYS_DES_PREFIX='J';
  end_body;
end_primitive;

primitive 'CONN9_H51826001_THMT','CONN9_H51826001_PIP2';
  pin
    'DN':
      PIN_NUMBER='(2)';
      BIDIRECTIONAL='TRUE';
      INPUT_LOAD='(-0.01,0.01)';
      OUTPUT_LOAD='(1.0,-1.0)';
    'DP':
      PIN_NUMBER='(3)';
      BIDIRECTIONAL='TRUE';
      INPUT_LOAD='(-0.01,0.01)';
      OUTPUT_LOAD='(1.0,-1.0)';
    'GND':
      PIN_NUMBER='(4)';
      PINUSE='GROUND';
      NO_LOAD_CHECK='Both';
      NO_IO_CHECK='Both';
      NO_ASSERT_CHECK='TRUE';
      NO_DIR_CHECK='TRUE';
      ALLOW_CONNECT='TRUE';
    'GND_DRAIN':
      PIN_NUMBER='(7)';
      PINUSE='GROUND';
      NO_LOAD_CHECK='Both';
      NO_IO_CHECK='Both';
      NO_ASSERT_CHECK='TRUE';
      NO_DIR_CHECK='TRUE';
      ALLOW_CONNECT='TRUE';
    'MH1':
      PIN_NUMBER='(MH1)';
      PINUSE='GROUND';
      NO_LOAD_CHECK='Both';
      NO_IO_CHECK='Both';
      NO_ASSERT_CHECK='TRUE';
      NO_DIR_CHECK='TRUE';
      ALLOW_CONNECT='TRUE';
    'MH2':
      PIN_NUMBER='(MH2)';
      PINUSE='GROUND';
      NO_LOAD_CHECK='Both';
      NO_IO_CHECK='Both';
      NO_ASSERT_CHECK='TRUE';
      NO_DIR_CHECK='TRUE';
      ALLOW_CONNECT='TRUE';
    'MH3':
      PIN_NUMBER='(MH3)';
      PINUSE='GROUND';
      NO_LOAD_CHECK='Both';
      NO_IO_CHECK='Both';
      NO_ASSERT_CHECK='TRUE';
      NO_DIR_CHECK='TRUE';
      ALLOW_CONNECT='TRUE';
    'MH4':
      PIN_NUMBER='(MH4)';
      PINUSE='GROUND';
      NO_LOAD_CHECK='Both';
      NO_IO_CHECK='Both';
      NO_ASSERT_CHECK='TRUE';
      NO_DIR_CHECK='TRUE';
      ALLOW_CONNECT='TRUE';
    'STDA_SSRXN':
      PIN_NUMBER='(5)';
      BIDIRECTIONAL='TRUE';
      INPUT_LOAD='(-0.01,0.01)';
      OUTPUT_LOAD='(1.0,-1.0)';
    'STDA_SSRXP':
      PIN_NUMBER='(6)';
      BIDIRECTIONAL='TRUE';
      INPUT_LOAD='(-0.01,0.01)';
      OUTPUT_LOAD='(1.0,-1.0)';
    'STDA_SSTXN':
      PIN_NUMBER='(8)';
      BIDIRECTIONAL='TRUE';
      INPUT_LOAD='(-0.01,0.01)';
      OUTPUT_LOAD='(1.0,-1.0)';
    'STDA_SSTXP':
      PIN_NUMBER='(9)';
      BIDIRECTIONAL='TRUE';
      INPUT_LOAD='(-0.01,0.01)';
      OUTPUT_LOAD='(1.0,-1.0)';
    'VBUS':
      PIN_NUMBER='(1)';
      BIDIRECTIONAL='TRUE';
      INPUT_LOAD='(-0.01,0.01)';
      OUTPUT_LOAD='(1.0,-1.0)';
  end_pin;
  body
    PART_NAME='CONN9_H51826001';
    PHYS_DES_PREFIX='J';
  end_body;
end_primitive;

END.
